FILE_TYPE = CONNECTIVITY;
{Allegro Design Entry HDL 17.2-2016 S081 (4005846) 1/11/2022}
"PAGE_NUMBER" = 285;
0"NC";
1"P3V3_AUX\g";
2"P3V3_AUX\g";
3"SW_P12V_PVCCIN_CPU1_FLT\g";
4"P3V3_AUX\g";
5"PVPP_HBM_CPU1\g";
6"GND\g";
7"GND\g";
8"GND\g";
9"GND\g";
10"GND\g";
11"GND\g";
12"GND\g";
13"GND\g";
14"GND\g";
15"GND\g";
16"PWRGD_PVPP_HBM_CPU1";
17"SH_PVPP_HBM_CPU1_P";
18"PVPP_HBM_CPU1_FB";
19"FM_HBM2_HBM3_VPP_SEL";
20"FM_HBM_VPP_SEL_CPU1_D";
21"SH_PVPP_HBM_CPU1_N";
22"PWRGD_PVPP_HBM_CPU1_R"CDS_PHYS_NET_NAME"PWRGD_PVPP_HBM_CPU1_R";
23"SW_PVPP_HBM_CPU1_SW";
24"PVPP_HBM_CPU1_REF";
25"SW_PVPP_HBM_CPU1_BST";
26"PVPP_HBM_CPU1_MODE";
27"PVPP_HBM_CPU1_VCC";
28"FM_PVPP_HBM_CPU1_EN";
29"PVPP_HBM_CPU1_CS";
%"Q_CAP"
"1","(-10525,2200)","0","pure_quanta","I1";
;
PART_NUMBER"CH5104KEB02"
TOLERANCE"10%"
PACK_TYPE"C0402"
VOLTAGE"25V"
MATERIAL"X6S"
VALUE"1UF"
LOCATION"PC644"
CDS_LIB"pure_quanta"
SEC_TYPE"C0402"
BOM_COST"VR_PCH"
SEC"1";
"B"
$PN"2"6;
"A"
$PN"1"27;
%"Q_RES"
"2","(-9175,2075)","0","pure_quanta","I10";
;
PART_NUMBER"CS29762FB05"
PACK_TYPE"0402LF"
MATERIAL"CHIP"
TOLERANCE"1%"
WATTAGE"1/16W"
VALUE"9.76K"
LOCATION"PR1339"
CDS_LIB"pure_quanta"
$SEC"1"
CDS_SEC"1";
"A"
$PN"1"29;
"B"
$PN"2"8;
%"Q_CAP"
"1","(-9750,2950)","0","pure_quanta","I11";
;
PART_NUMBER"TMP_QCH21006JB10"
PACK_TYPE"0402"
VALUE"1000PF"
VOLTAGE"50V"
TOLERANCE"5%"
MATERIAL"EMPTY"
LOCATION"C2445"
SEC_TYPE"0402"
CDS_LIB"pure_quanta"
LOCATION"C2445"
SEC"1";
"B"
$PN"2"9;
"A"
$PN"1"28;
%"UNIVERSAL_GND"
"1","(-9650,2725)","0","logical_power","I12";
;
HDL_POWER"GND"
CDS_LIB"logical_power";
"A"9;
%"Q_RES"
"2","(-9650,2950)","0","pure_quanta","I13";
;
PART_NUMBER"CS22002FB07"
WATTAGE"1/16W"
TOLERANCE"1%"
MATERIAL"CHIP"
VALUE"2K"
PACK_TYPE"0402LF"
LOCATION"R2374"
CDS_LIB"pure_quanta"
$SEC"1"
CDS_SEC"1";
"A"
$PN"1"28;
"B"
$PN"2"9;
%"Q_RES"
"1","(-10325,3350)","0","pure_quanta","I14";
;
PART_NUMBER"CS31002FB08"
MATERIAL"EMPTY"
TOLERANCE"1%"
VALUE"10K"
PACK_TYPE"0402LF"
WATTAGE"1/16W"
LOCATION"R2367"
CDS_LIB"pure_quanta"
$SEC"1"
CDS_SEC"1";
"B"
$PN"2"28;
"A"
$PN"1"2;
%"Q_CAP"
"1","(-10350,3900)","0","pure_quanta","I15";
;
PART_NUMBER"CH6223MEA01"
VOLTAGE"16V"
MATERIAL"X6S"
TOLERANCE"20%"
VALUE"22UF"
PACK_TYPE"C0805"
LOCATION"PC1260"
BOM_COST"VR_PCH"
CDS_LIB"pure_quanta"
$SEC"1"
CDS_SEC"1";
"B"
$PN"2"7;
"A"
$PN"1"3;
%"Q_CAP"
"1","(-9925,3900)","0","pure_quanta","I16";
;
PART_NUMBER"CH6223MEA01"
TOLERANCE"20%"
MATERIAL"X6S"
VALUE"22UF"
VOLTAGE"16V"
PACK_TYPE"C0805"
LOCATION"PC1261"
BOM_COST"VR_PCH"
CDS_LIB"pure_quanta"
$SEC"1"
CDS_SEC"1";
"B"
$PN"2"7;
"A"
$PN"1"3;
%"Q_CAP"
"1","(-9500,3900)","0","pure_quanta","I17";
;
PART_NUMBER"CH5103KEB01"
PACK_TYPE"C0402"
VALUE"1UF"
MATERIAL"X6S"
VOLTAGE"16V"
TOLERANCE"10%"
LOCATION"PC1262"
CDS_LIB"pure_quanta"
$SEC"1"
CDS_SEC"1";
"B"
$PN"2"7;
"A"
$PN"1"3;
%"Q_RES"
"1","(-8950,2900)","0","pure_quanta","I18";
;
PART_NUMBER"CS33012FB03"
VALUE"30.1K"
PACK_TYPE"0402LF"
MATERIAL"CHIP"
WATTAGE"1/16W"
TOLERANCE"1%"
LOCATION"PR3336"
CDS_LIB"pure_quanta"
$SEC"1"
CDS_SEC"1";
"B"
$PN"2"10;
"A"
$PN"1"26;
%"UNIVERSAL_GND"
"1","(-8525,2800)","0","logical_power","I19";
;
HDL_POWER"GND"
CDS_LIB"logical_power";
"A"10;
%"UNIVERSAL_GND"
"1","(-10525,1925)","0","logical_power","I2";
;
HDL_POWER"GND"
CDS_LIB"logical_power";
"A"6;
%"VCCAUX15"
"1","(-10800,4350)","0","logical_power","I20";
;
HDL_POWER"SW_P12V_PVCCIN_CPU1_FLT"
BOM_COST"VR_PCH"
CDS_LIB"logical_power";
"A"3;
%"UNIVERSAL_GND"
"1","(-7500,2025)","0","logical_power","I21";
;
HDL_POWER"GND"
CDS_LIB"logical_power";
"A"11;
%"UNIVERSAL_GND"
"1","(-7350,1875)","0","logical_power","I22";
;
HDL_POWER"GND"
CDS_LIB"logical_power";
"A"12;
%"Q_CAP"
"1","(-7350,2125)","0","pure_quanta","I23";
;
PART_NUMBER"TMP_QCH32203KB11"
VALUE"0.022UF"
MATERIAL"X7R"
VOLTAGE"16V"
PACK_TYPE"0402"
TOLERANCE"10%"
LOCATION"PC2002"
CDS_LIB"pure_quanta"
$SEC"1"
CDS_SEC"1";
"B"
$PN"2"12;
"A"
$PN"1"24;
%"Q_CAP"
"1","(-6850,2000)","0","pure_quanta","I24";
;
PART_NUMBER"CH4104K1B00"
MATERIAL"X7R"
VALUE"0.1UF"
VOLTAGE"25V"
PACK_TYPE"0402"
TOLERANCE"10%"
LOCATION"PC1264"
CDS_LIB"pure_quanta"
$SEC"1"
CDS_SEC"1";
"B"
$PN"2"21;
"A"
$PN"1"24;
%"RS53318LR"
"1","(-8000,3000)","0","pure_quanta","I25";
;
PART_NUMBER"AL053318002"
MATERIAL"IC"
VALUE"RS53318LR"
PART_TYPE"SMLF"
LOCATION"PU80"
SEC_TYPE""
CDS_LIB"pure_quanta"
NEEDS_NO_SIZE"TRUE"
CDS_LMAN_SYM_OUTLINE"-250,725,250,-725"
SEC"1";
"VIN2"
$PN"21"3;
"CS"
$PN"3"29;
"MODE"
$PN"4"26;
"REF"
$PN"5"24;
"SW"
$PN"20"23;
"RTN"
$PN"6"21;
"VCC"
$PN"19"27;
"AGND"
$PN"2"11;
"FB"
$PN"7"18;
"BST"
$PN"1"25;
"EN"
$PN"8"28;
"PGND"
$PN"11_18"11;
"PGOOD"
$PN"9"22;
"VIN1"
$PN"10"3;
%"Q_CAP"
"1","(-6725,3400)","0","pure_quanta","I26";
;
PART_NUMBER"CH4224K1B01"
VALUE"0.22UF"
VOLTAGE"25V"
PACK_TYPE"C0402"
TOLERANCE"10%"
MATERIAL"X7R"
LOCATION"PC1265"
CDS_LIB"pure_quanta"
$SEC"1"
CDS_SEC"1";
"B"
$PN"2"23;
"A"
$PN"1"25;
%"Q_RES"
"2","(-6600,4200)","0","pure_quanta","I27";
;
PART_NUMBER"CS31002FB08"
TOLERANCE"1%"
MATERIAL"CHIP"
PACK_TYPE"0402LF"
WATTAGE"1/16W"
VALUE"10K"
LOCATION"R2583"
CDS_LIB"pure_quanta"
BOM_COST"VR_PCH"
$SEC"1"
CDS_SEC"1";
"A"
$PN"1"4;
"B"
$PN"2"22;
%"Q_RES"
"2","(-6375,2000)","0","pure_quanta","I28";
;
PART_NUMBER"CS31132BB02"
PACK_TYPE"0402LF"
VALUE"11.3K"
TOLERANCE"0.1%"
WATTAGE"1/16W"
MATERIAL"CHIP"
LOCATION"PR1314"
CDS_LIB"pure_quanta"
BOM_COST"VR_PCH"
$SEC"1"
CDS_SEC"1";
"A"
$PN"1"18;
"B"
$PN"2"21;
%"MOSFET_N"
"1","(-5625,1800)","2","pure_quanta","I29";
;
PART_NUMBER"BAM138K0000"
MATERIAL"EMPTY"
VALUE"BSS138K"
LOCATION"PU174"
MANUF_PN"BSS138K"
CDS_LMAN_SYM_OUTLINE"-50,50,100,-150"
CDS_LIB"pure_quanta"
PACK_TYPE"SMLF"
$SEC"1"
CDS_SEC"1";
"GATE"
$PN"G"19;
"SOURCE"
$PN"S"21;
"DRAIN"
$PN"D"20;
%"Q_RES"
"2","(-10525,2650)","0","pure_quanta","I3";
;
PART_NUMBER"CS00002JB13"
PACK_TYPE"0402LF"
VALUE"0"
TOLERANCE"5%"
WATTAGE"1/16W"
MATERIAL"CHIP"
LOCATION"PR1338"
CDS_LIB"pure_quanta"
$SEC"1"
CDS_SEC"1";
"A"
$PN"1"1;
"B"
$PN"2"27;
%"Q_RES"
"1","(-5700,2025)","0","pure_quanta","I30";
;
PART_NUMBER"CS32612BB02"
MATERIAL"EMPTY"
VALUE"26.1K"
PACK_TYPE"0402LF"
WATTAGE"1/16W"
TOLERANCE"0.1%"
LOCATION"PR2381"
CDS_LIB"pure_quanta"
$SEC"1"
CDS_SEC"1";
"B"
$PN"2"20;
"A"
$PN"1"18;
%"Q_CAP"
"1","(-4400,1925)","0","pure_quanta","I32";
;
PART_NUMBER"TMP_QCH31004KB17"
PACK_TYPE"0402"
MATERIAL"X7R"
TOLERANCE"10%"
VOLTAGE"25V"
VALUE"0.01UF"
LOCATION"PC2282"
CDS_LIB"pure_quanta"
$SEC"1"
CDS_SEC"1";
"B"
$PN"2"21;
"A"
$PN"1"17;
%"Q_INDUCTOR"
"1","(-5900,3200)","0","pure_quanta","I33";
;
PART_NUMBER"CV+68F5MZ05"
VALUE"0.68UH"
MATERIAL"IND"
PACK_TYPE"SMLF"
LOCATION"PL119"
BOM_COST"VR_PCH"
NEEDS_NO_SIZE"TRUE"
CDS_LIB"pure_quanta"
$SEC"1"
CDS_SEC"1";
"1"
$PN"1"23;
"2"
$PN"2"5;
%"Q_RES"
"1","(-5700,2425)","0","pure_quanta","I34";
;
PART_NUMBER"CS33832BB06"
TOLERANCE"0.1%"
PACK_TYPE"0402LF"
MATERIAL"CHIP"
VALUE"38.3K"
WATTAGE"1/16W"
LOCATION"PR1340"
CDS_LIB"pure_quanta"
$SEC"1"
CDS_SEC"1";
"B"
$PN"2"17;
"A"
$PN"1"18;
%"Q_CAP"
"2","(-5700,2250)","0","pure_quanta","I35";
;
PART_NUMBER"TMP_QCH16806KB17"
VALUE"680PF"
TOLERANCE"10%"
MATERIAL"X7R"
PACK_TYPE"0402"
VOLTAGE"50V"
LOCATION"PC1266"
CDS_LIB"pure_quanta"
$SEC"1"
CDS_SEC"1";
"A"
$PN"1"18;
"B"
$PN"2"17;
%"Q_CAP"
"2","(-6175,3750)","0","pure_quanta","I36";
;
PART_NUMBER"TMP_QCH21006JB10"
MATERIAL"X7R"
PACK_TYPE"0402"
TOLERANCE"5%"
VOLTAGE"50V"
VALUE"1000PF"
LOCATION"C2460"
CDS_LIB"pure_quanta"
$SEC"1"
CDS_SEC"1";
"A"
$PN"1"22;
"B"
$PN"2"13;
%"Q_RES"
"1","(-6175,3875)","0","pure_quanta","I37";
;
PART_NUMBER"CS00002JB13"
WATTAGE"1/16W"
PACK_TYPE"0402LF"
VALUE"0"
TOLERANCE"5%"
MATERIAL"CHIP"
LOCATION"R2380"
CDS_LIB"pure_quanta"
$SEC"1"
CDS_SEC"1";
"B"
$PN"2"16;
"A"
$PN"1"22;
%"UNIVERSAL_GND"
"1","(-5700,3650)","0","logical_power","I38";
;
HDL_POWER"GND"
CDS_LIB"logical_power";
"A"13;
%"Q_CAP"
"1","(-5275,2975)","0","pure_quanta","I39";
;
PART_NUMBER"CH4104K1B00"
PACK_TYPE"0402"
TOLERANCE"10%"
VALUE"0.1UF"
MATERIAL"X7R"
VOLTAGE"25V"
LOCATION"PC1267"
CDS_LIB"pure_quanta"
$SEC"1"
CDS_SEC"1";
"B"
$PN"2"15;
"A"
$PN"1"5;
%"Q_CAP"
"1","(-4850,2975)","0","pure_quanta","I40";
;
PART_NUMBER"CH622KMEA03"
TOLERANCE"20%"
PACK_TYPE"C0805"
VALUE"22UF"
MATERIAL"X6S"
VOLTAGE"4V"
LOCATION"PC1268"
CDS_LIB"pure_quanta"
BOM_COST"VR_PCH"
$SEC"1"
CDS_SEC"1";
"B"
$PN"2"15;
"A"
$PN"1"5;
%"Q_CAP"
"1","(-4475,2975)","0","pure_quanta","I41";
;
PART_NUMBER"CH622KMEA03"
VALUE"22UF"
VOLTAGE"4V"
TOLERANCE"20%"
PACK_TYPE"C0805"
MATERIAL"X6S"
LOCATION"PC1269"
CDS_LIB"pure_quanta"
BOM_COST"VR_PCH"
$SEC"1"
CDS_SEC"1";
"B"
$PN"2"15;
"A"
$PN"1"5;
%"UNIVERSAL_POWER"
"1","(-6600,4450)","0","logical_power","I43";
;
HDL_POWER"P3V3_AUX"
CDS_LIB"logical_power";
"A"4;
%"Q_SHORT"
"1","(-3950,1425)","0","pure_quanta","I44";
;
PART_NUMBER"SHORT6"
PACK_TYPE"SM"
MATERIAL"EMPTY"
LOCATION"PJ67"
BOM_COST"VR_PCH"
NEEDS_NO_SIZE"TRUE"
CDS_LIB"pure_quanta"
$SEC"1"
CDS_SEC"1";
"1"
$PN"1"21;
"2"
$PN"2"14;
%"UNIVERSAL_GND"
"1","(-3275,1100)","0","logical_power","I45";
;
HDL_POWER"GND"
CDS_LIB"logical_power";
"A"14;
%"Q_SHORT"
"1","(-3950,2425)","0","pure_quanta","I46";
;
PART_NUMBER"SHORT6"
MATERIAL"EMPTY"
PACK_TYPE"SM"
LOCATION"PJ66"
BOM_COST"VR_PCH"
NEEDS_NO_SIZE"TRUE"
CDS_LIB"pure_quanta"
$SEC"1"
CDS_SEC"1";
"1"
$PN"1"17;
"2"
$PN"2"5;
%"Q_CAP"
"1","(-4100,2975)","0","pure_quanta","I47";
;
PART_NUMBER"CH622KMEA03"
MATERIAL"X6S"
TOLERANCE"20%"
VOLTAGE"4V"
VALUE"22UF"
PACK_TYPE"C0805"
LOCATION"PC1270"
CDS_LIB"pure_quanta"
BOM_COST"VR_PCH"
$SEC"1"
CDS_SEC"1";
"B"
$PN"2"15;
"A"
$PN"1"5;
%"UNIVERSAL_GND"
"1","(-3700,2600)","0","logical_power","I48";
;
HDL_POWER"GND"
CDS_LIB"logical_power";
"A"15;
%"Q_CAPP"
"1","(-3700,2975)","0","pure_quanta","I49";
;
PART_NUMBER"CC75601MD16"
PACK_TYPE"THLF"
MATERIAL"OSCON"
VALUE"560UF"
TOLERANCE"20%"
VOLTAGE"6.3V"
LOCATION"PC1771"
BOM_COST"VR_PCH"
CDS_LIB"pure_quanta"
$SEC"1"
CDS_SEC"1";
"A"
$PN"1"5;
"B"
$PN"2"15;
%"UNIVERSAL_POWER"
"1","(-10525,2875)","0","logical_power","I5";
;
HDL_POWER"P3V3_AUX"
CDS_LIB"logical_power";
"A"1;
%"UNIVERSAL_POWER"
"1","(-3275,3400)","0","logical_power","I50";
;
HDL_POWER"PVPP_HBM_CPU1"
CDS_LIB"logical_power";
"A"5;
%"VCCAUX15"
"1","(-11125,3425)","0","logical_power","I6";
;
HDL_POWER"P3V3_AUX"
BOM_COST"VR_PCH"
CDS_LIB"logical_power";
"A"2;
%"UNIVERSAL_GND"
"1","(-10800,3550)","0","logical_power","I7";
;
HDL_POWER"GND"
CDS_LIB"logical_power";
"A"7;
%"Q_CAP"
"1","(-10800,3900)","0","pure_quanta","I8";
;
PART_NUMBER"CH6223MEA01"
MATERIAL"X6S"
VALUE"22UF"
VOLTAGE"16V"
PACK_TYPE"C0805"
TOLERANCE"20%"
LOCATION"PC1259"
CDS_LIB"pure_quanta"
BOM_COST"VR_PCH"
$SEC"1"
CDS_SEC"1";
"B"
$PN"2"7;
"A"
$PN"1"3;
%"UNIVERSAL_GND"
"1","(-9175,1825)","0","logical_power","I9";
;
HDL_POWER"GND"
CDS_LIB"logical_power";
"A"8;
END.
